# TIMECARD (Time Appliance Project (Time Card)) — schematic netlist excerpt (pin names and nets, part order shuffled) for the footprints in the layout excerpt that follows; sources: Cadence DE-HDL packaged netlist, KiCad conversion of R4006-B0001-02_R01.brd

TP49  TP_PIONT  pkg TP010CT020B030_PTH  page 25 : \1\ = CLK_200M_OE
R13  RESISTOR  10KOHM 1%  pkg SMC_0402R_H016  page 27 : \1\ = XP12R0V ; \2\ = XP12R0V_A_PG
ME5  MEC_NPTH  pkg MTH100C240N  page 34

(kicad_pcb
	(version 20260206)
	(generator "pcbnew")
	(generator_version "10.0")
	(general
		(thickness 1.6)
		(legacy_teardrops no)
	)
	(paper "A4")
	(title_block
		(title "timecard-production-celestica-r4006 — R4006-B0001-02_R01.brd")
		(comment 1 "Time Appliance Project (Time Card) / footprints 243-245 of 1113")
	)
	(layers
		(0 "F.Cu" signal "TOP")
		(4 "In1.Cu" signal "L02_GND1")
		(6 "In2.Cu" signal "L03_SIG1")
		(8 "In3.Cu" signal "L04_GND2")
		(10 "In4.Cu" signal "L05_VCC1")
		(12 "In5.Cu" signal "L06_VCC2")
		(14 "In6.Cu" signal "L07_GND3")
		(16 "In7.Cu" signal "L08_SIG2")
		(18 "In8.Cu" signal "L09_GND4")
		(2 "B.Cu" signal "BOTTOM")
		(9 "F.Adhes" user "F.Adhesive")
		(11 "B.Adhes" user "B.Adhesive")
		(13 "F.Paste" user "Package Geometry/Pastemask Top")
		(15 "B.Paste" user "Package Geometry/Pastemask Bottom")
		(5 "F.SilkS" user "Ref Des/Silkscreen Top")
		(7 "B.SilkS" user "Ref Des/Silkscreen Bottom")
		(1 "F.Mask" user "Board Geometry/Soldermask Top")
		(3 "B.Mask" user "Board Geometry/Soldermask Bottom")
		(17 "Dwgs.User" user "User.Drawings")
		(19 "Cmts.User" user "User.Comments")
		(21 "Eco1.User" user "User.Eco1")
		(23 "Eco2.User" user "User.Eco2")
		(25 "Edge.Cuts" user "Board Geometry/Outline")
		(27 "Margin" user)
		(31 "F.CrtYd" user "Package Geometry/Place Bound Top")
		(29 "B.CrtYd" user "Package Geometry/Place Bound Bottom")
		(35 "F.Fab" user "Ref Des/Assembly Top")
		(33 "B.Fab" user "Ref Des/Assembly Bottom")
	)
	(footprint ""
		(layer "F.Cu")
		(at 106.807 -20.828)
		(property "Reference" "TP49"
			(at 0.03937 4.5212 90)
			(unlocked yes)
			(layer "F.SilkS")
			(effects
				(font
					(size 0.7874 0.5842)
					(thickness 0.1524)
				)
				(justify left)
			)
		)
		(property "Value" ""
			(at 0 0 0)
			(layer "F.Fab")
			(effects
				(font
					(size 1.27 1.27)
				)
			)
		)
		(property "Device Type" "TP_PIONT-TP010CT020B030_PTH-TPA"
			(at -1.341882 0.996696 0)
			(unlocked yes)
			(layer "F.Fab")
			(hide yes)
			(effects
				(font
					(size 0.7874 0.5842)
					(thickness 0.000001)
				)
				(justify left)
			)
		)
		(duplicate_pad_numbers_are_jumpers no)
		(fp_poly
			(pts
				(arc
					(start 0.889 0)
					(mid -0.889 0)
					(end 0.889 0)
				)
			)
			(stroke
				(width 0)
				(type default)
			)
			(fill no)
			(layer "B.CrtYd")
		)
		(fp_poly
			(pts
				(arc
					(start 0.889 0)
					(mid -0.889 0)
					(end 0.889 0)
				)
			)
			(stroke
				(width 0)
				(type default)
			)
			(fill no)
			(layer "F.CrtYd")
		)
		(pad "1" thru_hole circle
			(at 0 0)
			(size 0.508 0.508)
			(drill 0.254)
			(layers "*.Cu" "*.Mask")
			(remove_unused_layers no)
			(net "CLK_200M_OE")
			(clearance 0.1016)
			(padstack
				(mode front_inner_back)
				(layer "Inner"
					(shape circle)
					(size 0.508 0.508)
					(clearance 0.1016)
				)
				(layer "B.Cu"
					(shape circle)
					(size 0.762 0.762)
					(clearance -0.0254)
				)
			)
		)
	)
	(footprint ""
		(layer "F.Cu")
		(at 141.732 -100.584 180)
		(property "Reference" "R13"
			(at -2.032 -0.66675 0)
			(unlocked yes)
			(layer "F.SilkS")
			(effects
				(font
					(size 0.635 0.4064)
					(thickness 0.1524)
				)
			)
		)
		(property "Value" "VAL*"
			(at 0.02032 2.13233 180)
			(unlocked yes)
			(layer "F.Fab")
			(hide yes)
			(effects
				(font
					(size 0.7874 0.5842)
					(thickness 0.1524)
				)
			)
		)
		(property "Device Type" "RESISTOR-G155-11002-01,10KOHM,A"
			(at 0.008382 1.210564 180)
			(unlocked yes)
			(layer "F.Fab")
			(hide yes)
			(effects
				(font
					(size 0.7874 0.5842)
					(thickness 0.1524)
				)
			)
		)
		(property "User Part Number" "PARTNUM*"
			(at 0.02032 4.024884 180)
			(unlocked yes)
			(layer "Cmts.User")
			(hide yes)
			(effects
				(font
					(size 0.7874 0.5842)
					(thickness 0.1524)
				)
			)
		)
		(property "Tolerance" "TOL*"
			(at 0.044704 3.05435 180)
			(unlocked yes)
			(layer "Cmts.User")
			(hide yes)
			(effects
				(font
					(size 0.7874 0.5842)
					(thickness 0.1524)
				)
			)
		)
		(duplicate_pad_numbers_are_jumpers no)
		(fp_line
			(start 1.143 0.5588)
			(end 1.143 -0.5588)
			(stroke
				(width 0.1)
				(type default)
			)
			(layer "F.SilkS")
		)
		(fp_line
			(start 1.143 -0.5588)
			(end -1.143 -0.5588)
			(stroke
				(width 0.1)
				(type default)
			)
			(layer "F.SilkS")
		)
		(fp_line
			(start -1.143 0.5588)
			(end 1.143 0.5588)
			(stroke
				(width 0.1)
				(type default)
			)
			(layer "F.SilkS")
		)
		(fp_line
			(start -1.143 -0.5588)
			(end -1.143 0.5588)
			(stroke
				(width 0.1)
				(type default)
			)
			(layer "F.SilkS")
		)
		(fp_rect
			(start -1.143 0.5588)
			(end 1.143 -0.5588)
			(stroke
				(width 0)
				(type default)
			)
			(fill no)
			(layer "F.CrtYd")
		)
		(fp_line
			(start 0.508 0.3048)
			(end 0.508 -0.3048)
			(stroke
				(width 0.1)
				(type default)
			)
			(layer "F.Fab")
		)
		(fp_line
			(start 0.508 -0.3048)
			(end -0.508 -0.3048)
			(stroke
				(width 0.1)
				(type default)
			)
			(layer "F.Fab")
		)
		(fp_line
			(start -0.508 0.3048)
			(end 0.508 0.3048)
			(stroke
				(width 0.1)
				(type default)
			)
			(layer "F.Fab")
		)
		(fp_line
			(start -0.508 -0.3048)
			(end -0.508 0.3048)
			(stroke
				(width 0.1)
				(type default)
			)
			(layer "F.Fab")
		)
		(pad "1" smd rect
			(at -0.5334 0 180)
			(size 0.7112 0.6096)
			(layers "F.Cu" "F.Mask" "F.Paste")
			(net "XP12R0V")
		)
		(pad "2" smd rect
			(at 0.5334 0 180)
			(size 0.7112 0.6096)
			(layers "F.Cu" "F.Mask" "F.Paste")
			(net "XP12R0V_A_PG")
		)
		(zone
			(layer "F.Cu")
			(hatch none 0.5)
			(connect_pads
				(clearance 0)
			)
			(min_thickness 0.25)
			(keepout
				(tracks allowed)
				(vias not_allowed)
				(pads allowed)
				(copperpour not_allowed)
				(footprints allowed)
			)
			(placement
				(enabled no)
				(sheetname "")
			)
			(fill
				(thermal_gap 0.5)
				(thermal_bridge_width 0.5)
				(island_removal_mode 0)
			)
			(polygon
				(pts
					(xy 141.8082 -100.8888) (xy 141.6558 -100.8888) (xy 141.6558 -100.2792) (xy 141.8082 -100.2792)
				)
			)
		)
	)
	(footprint ""
		(layer "F.Cu")
		(at 37.101018 -68.082922)
		(property "Reference" "ME5"
			(at -1.795018 -4.140708 0)
			(unlocked yes)
			(layer "F.SilkS")
			(effects
				(font
					(size 0.7874 0.5842)
					(thickness 0.1524)
				)
			)
		)
		(property "Value" ""
			(at 0 0 0)
			(layer "F.Fab")
			(effects
				(font
					(size 1.27 1.27)
				)
			)
		)
		(duplicate_pad_numbers_are_jumpers no)
		(fp_poly
			(pts
				(arc
					(start 3.556 0)
					(mid -3.556 0)
					(end 3.556 0)
				)
			)
			(stroke
				(width 0)
				(type default)
			)
			(fill no)
			(layer "B.CrtYd")
		)
		(fp_poly
			(pts
				(arc
					(start 3.556 0)
					(mid -3.556 0)
					(end 3.556 0)
				)
			)
			(stroke
				(width 0)
				(type default)
			)
			(fill no)
			(layer "F.CrtYd")
		)
		(fp_circle
			(center 0 0)
			(end 3.048 0)
			(stroke
				(width 0.1)
				(type default)
			)
			(fill no)
			(layer "B.Fab")
		)
		(fp_circle
			(center 0 0)
			(end 3.048 0)
			(stroke
				(width 0.1)
				(type default)
			)
			(fill no)
			(layer "F.Fab")
		)
		(pad "" np_thru_hole circle
			(at 0 0)
			(size 2.286 2.286)
			(drill 2.54)
			(layers "*.Cu" "*.Mask")
			(padstack
				(mode front_inner_back)
				(layer "Inner"
					(shape circle)
					(size 2.286 2.286)
					(clearance 0.4445)
				)
				(layer "B.Cu"
					(shape circle)
					(size 2.286 2.286)
				)
			)
		)
		(zone
			(layers "F.Cu" "B.Cu" "In1.Cu" "In2.Cu" "In3.Cu" "In4.Cu" "In5.Cu" "In6.Cu"
				"In7.Cu" "In8.Cu"
			)
			(hatch none 0.5)
			(connect_pads
				(clearance 0)
			)
			(min_thickness 0.25)
			(keepout
				(tracks not_allowed)
				(vias allowed)
				(pads allowed)
				(copperpour not_allowed)
				(footprints allowed)
			)
			(placement
				(enabled no)
				(sheetname "")
			)
			(fill
				(thermal_gap 0.5)
				(thermal_bridge_width 0.5)
				(island_removal_mode 0)
			)
			(polygon
				(pts
					(arc
						(start 38.675818 -68.082922)
						(mid 35.526218 -68.082922)
						(end 38.675818 -68.082922)
					)
				)
			)
		)
	)
)
